(kicad_pcb
	(version 20260206)
	(generator "pcbnew")
	(generator_version "10.0")
	(general
		(thickness 1.6)
		(legacy_teardrops no)
	)
	(paper "A4")
	(title_block
		(title "04192023_DAF0TMB3IC0_F0TG_MB_C_brd_V02_OCP.brd")
		(comment 1 "Grand Teton / footprints 7603-7608 of 8354")
	)
	(layers
		(0 "F.Cu" signal "TOP")
		(4 "In1.Cu" signal "GND")
		(6 "In2.Cu" signal "IN1")
		(8 "In3.Cu" signal "GND1")
		(10 "In4.Cu" signal "IN2")
		(12 "In5.Cu" signal "GND2")
		(14 "In6.Cu" signal "IN3")
		(16 "In7.Cu" signal "GND3")
		(18 "In8.Cu" signal "VCC")
		(20 "In9.Cu" signal "VCC1")
		(22 "In10.Cu" signal "GND4")
		(24 "In11.Cu" signal "IN4")
		(26 "In12.Cu" signal "GND5")
		(28 "In13.Cu" signal "IN5")
		(30 "In14.Cu" signal "GND6")
		(32 "In15.Cu" signal "IN6")
		(34 "In16.Cu" signal "GND7")
		(2 "B.Cu" signal "BOTTOM")
		(9 "F.Adhes" user "F.Adhesive")
		(11 "B.Adhes" user "B.Adhesive")
		(13 "F.Paste" user "Package Geometry/Pastemask Top")
		(15 "B.Paste" user "Package Geometry/Pastemask Bottom")
		(5 "F.SilkS" user "Ref Des/Silkscreen Top")
		(7 "B.SilkS" user "Ref Des/Silkscreen Bottom")
		(1 "F.Mask" user "Board Geometry/Soldermask Top")
		(3 "B.Mask" user "Board Geometry/Soldermask Bottom")
		(17 "Dwgs.User" user "User.Drawings")
		(19 "Cmts.User" user "User.Comments")
		(21 "Eco1.User" user "User.Eco1")
		(23 "Eco2.User" user "User.Eco2")
		(25 "Edge.Cuts" user "Board Geometry/Outline")
		(27 "Margin" user)
		(31 "F.CrtYd" user "Package Geometry/Place Bound Top")
		(29 "B.CrtYd" user "Package Geometry/Place Bound Bottom")
		(35 "F.Fab" user "Ref Des/Assembly Top")
		(33 "B.Fab" user "Ref Des/Assembly Bottom")
	)
	(footprint ""
		(layer "B.Cu")
		(at 15.436088 -135.48741 90)
		(property "Reference" "R4077"
			(at 0 0 90)
			(layer "B.SilkS")
			(hide yes)
			(effects
				(font
					(size 1.27 1.27)
				)
				(justify mirror)
			)
		)
		(property "Value" ""
			(at 0 0 90)
			(layer "B.Fab")
			(effects
				(font
					(size 1.27 1.27)
				)
				(justify mirror)
			)
		)
		(duplicate_pad_numbers_are_jumpers no)
		(fp_line
			(start 0.7874 -0.4064)
			(end -0.7874 -0.4064)
			(stroke
				(width 0.1524)
				(type default)
			)
			(layer "B.SilkS")
		)
		(fp_line
			(start -0.7874 -0.4064)
			(end -0.7874 0.4064)
			(stroke
				(width 0.1524)
				(type default)
			)
			(layer "B.SilkS")
		)
		(fp_line
			(start 0.7874 0.4064)
			(end 0.7874 -0.4064)
			(stroke
				(width 0.1524)
				(type default)
			)
			(layer "B.SilkS")
		)
		(fp_line
			(start -0.7874 0.4064)
			(end 0.7874 0.4064)
			(stroke
				(width 0.1524)
				(type default)
			)
			(layer "B.SilkS")
		)
		(fp_line
			(start 0.67945 -0.305054)
			(end 0.12065 -0.305054)
			(stroke
				(width 0.1)
				(type default)
			)
			(layer "B.Fab")
		)
		(fp_line
			(start 0.12065 -0.305054)
			(end 0.12065 -0.2794)
			(stroke
				(width 0.1)
				(type default)
			)
			(layer "B.Fab")
		)
		(fp_line
			(start -0.12065 -0.3048)
			(end -0.67945 -0.3048)
			(stroke
				(width 0.1)
				(type default)
			)
			(layer "B.Fab")
		)
		(fp_line
			(start -0.67945 -0.3048)
			(end -0.67945 0.3048)
			(stroke
				(width 0.1)
				(type default)
			)
			(layer "B.Fab")
		)
		(fp_line
			(start 0.12065 -0.2794)
			(end -0.12065 -0.2794)
			(stroke
				(width 0.1)
				(type default)
			)
			(layer "B.Fab")
		)
		(fp_line
			(start -0.12065 -0.2794)
			(end -0.12065 -0.3048)
			(stroke
				(width 0.1)
				(type default)
			)
			(layer "B.Fab")
		)
		(fp_line
			(start 0.12065 0.2794)
			(end 0.12065 0.3048)
			(stroke
				(width 0.1)
				(type default)
			)
			(layer "B.Fab")
		)
		(fp_line
			(start -0.120396 0.2794)
			(end 0.12065 0.2794)
			(stroke
				(width 0.1)
				(type default)
			)
			(layer "B.Fab")
		)
		(fp_line
			(start 0.67945 0.3048)
			(end 0.67945 -0.305054)
			(stroke
				(width 0.1)
				(type default)
			)
			(layer "B.Fab")
		)
		(fp_line
			(start 0.12065 0.3048)
			(end 0.67945 0.3048)
			(stroke
				(width 0.1)
				(type default)
			)
			(layer "B.Fab")
		)
		(fp_line
			(start -0.120396 0.3048)
			(end -0.120396 0.2794)
			(stroke
				(width 0.1)
				(type default)
			)
			(layer "B.Fab")
		)
		(fp_line
			(start -0.67945 0.3048)
			(end -0.120396 0.3048)
			(stroke
				(width 0.1)
				(type default)
			)
			(layer "B.Fab")
		)
		(pad "1" smd circle
			(at 0.40005 0 270)
			(size 0 0)
			(layers "B.Cu" "B.Mask" "B.Paste")
			(net "VFG3P3_CLK_GEN")
		)
		(pad "2" smd circle
			(at -0.40005 0 270)
			(size 0 0)
			(layers "B.Cu" "B.Mask" "B.Paste")
			(net "VFG_3P3A_CLK_GEN")
		)
	)
	(footprint ""
		(layer "B.Cu")
		(at 395.152372 -395.127988 -90)
		(property "Reference" "C997"
			(at 0 0 90)
			(layer "B.SilkS")
			(hide yes)
			(effects
				(font
					(size 1.27 1.27)
				)
				(justify mirror)
			)
		)
		(property "Value" ""
			(at 0 0 90)
			(layer "B.Fab")
			(effects
				(font
					(size 1.27 1.27)
				)
				(justify mirror)
			)
		)
		(duplicate_pad_numbers_are_jumpers no)
		(fp_line
			(start -0.7874 0.4064)
			(end 0.7874 0.4064)
			(stroke
				(width 0.1524)
				(type default)
			)
			(layer "B.SilkS")
		)
		(fp_line
			(start 0.7874 0.4064)
			(end 0.7874 -0.4064)
			(stroke
				(width 0.1524)
				(type default)
			)
			(layer "B.SilkS")
		)
		(fp_line
			(start -0.7874 -0.4064)
			(end -0.7874 0.4064)
			(stroke
				(width 0.1524)
				(type default)
			)
			(layer "B.SilkS")
		)
		(fp_line
			(start 0.7874 -0.4064)
			(end -0.7874 -0.4064)
			(stroke
				(width 0.1524)
				(type default)
			)
			(layer "B.SilkS")
		)
		(fp_line
			(start -0.67945 0.3048)
			(end -0.120396 0.3048)
			(stroke
				(width 0.1)
				(type default)
			)
			(layer "B.Fab")
		)
		(fp_line
			(start -0.120396 0.3048)
			(end -0.120396 0.2794)
			(stroke
				(width 0.1)
				(type default)
			)
			(layer "B.Fab")
		)
		(fp_line
			(start 0.12065 0.3048)
			(end 0.67945 0.3048)
			(stroke
				(width 0.1)
				(type default)
			)
			(layer "B.Fab")
		)
		(fp_line
			(start 0.67945 0.3048)
			(end 0.67945 -0.305054)
			(stroke
				(width 0.1)
				(type default)
			)
			(layer "B.Fab")
		)
		(fp_line
			(start -0.120396 0.2794)
			(end 0.12065 0.2794)
			(stroke
				(width 0.1)
				(type default)
			)
			(layer "B.Fab")
		)
		(fp_line
			(start 0.12065 0.2794)
			(end 0.12065 0.3048)
			(stroke
				(width 0.1)
				(type default)
			)
			(layer "B.Fab")
		)
		(fp_line
			(start -0.12065 -0.2794)
			(end -0.12065 -0.3048)
			(stroke
				(width 0.1)
				(type default)
			)
			(layer "B.Fab")
		)
		(fp_line
			(start 0.12065 -0.2794)
			(end -0.12065 -0.2794)
			(stroke
				(width 0.1)
				(type default)
			)
			(layer "B.Fab")
		)
		(fp_line
			(start -0.67945 -0.3048)
			(end -0.67945 0.3048)
			(stroke
				(width 0.1)
				(type default)
			)
			(layer "B.Fab")
		)
		(fp_line
			(start -0.12065 -0.3048)
			(end -0.67945 -0.3048)
			(stroke
				(width 0.1)
				(type default)
			)
			(layer "B.Fab")
		)
		(fp_line
			(start 0.12065 -0.305054)
			(end 0.12065 -0.2794)
			(stroke
				(width 0.1)
				(type default)
			)
			(layer "B.Fab")
		)
		(fp_line
			(start 0.67945 -0.305054)
			(end 0.12065 -0.305054)
			(stroke
				(width 0.1)
				(type default)
			)
			(layer "B.Fab")
		)
		(pad "1" smd circle
			(at 0.40005 0 90)
			(size 0 0)
			(layers "B.Cu" "B.Mask" "B.Paste")
			(net "P1V8_CPU0_RT_1D")
		)
		(pad "2" smd circle
			(at -0.40005 0 90)
			(size 0 0)
			(layers "B.Cu" "B.Mask" "B.Paste")
			(net "GND")
		)
	)
	(footprint ""
		(layer "B.Cu")
		(at 19.727418 -409.04287 90)
		(property "Reference" "PR6816"
			(at 0 0 90)
			(layer "B.SilkS")
			(hide yes)
			(effects
				(font
					(size 1.27 1.27)
				)
				(justify mirror)
			)
		)
		(property "Value" ""
			(at 0 0 90)
			(layer "B.Fab")
			(effects
				(font
					(size 1.27 1.27)
				)
				(justify mirror)
			)
		)
		(duplicate_pad_numbers_are_jumpers no)
		(fp_line
			(start 0.7874 -0.4064)
			(end -0.7874 -0.4064)
			(stroke
				(width 0.1524)
				(type default)
			)
			(layer "B.SilkS")
		)
		(fp_line
			(start -0.7874 -0.4064)
			(end -0.7874 0.4064)
			(stroke
				(width 0.1524)
				(type default)
			)
			(layer "B.SilkS")
		)
		(fp_line
			(start 0.7874 0.4064)
			(end 0.7874 -0.4064)
			(stroke
				(width 0.1524)
				(type default)
			)
			(layer "B.SilkS")
		)
		(fp_line
			(start -0.7874 0.4064)
			(end 0.7874 0.4064)
			(stroke
				(width 0.1524)
				(type default)
			)
			(layer "B.SilkS")
		)
		(fp_line
			(start 0.67945 -0.305054)
			(end 0.12065 -0.305054)
			(stroke
				(width 0.1)
				(type default)
			)
			(layer "B.Fab")
		)
		(fp_line
			(start 0.12065 -0.305054)
			(end 0.12065 -0.2794)
			(stroke
				(width 0.1)
				(type default)
			)
			(layer "B.Fab")
		)
		(fp_line
			(start -0.12065 -0.3048)
			(end -0.67945 -0.3048)
			(stroke
				(width 0.1)
				(type default)
			)
			(layer "B.Fab")
		)
		(fp_line
			(start -0.67945 -0.3048)
			(end -0.67945 0.3048)
			(stroke
				(width 0.1)
				(type default)
			)
			(layer "B.Fab")
		)
		(fp_line
			(start 0.12065 -0.2794)
			(end -0.12065 -0.2794)
			(stroke
				(width 0.1)
				(type default)
			)
			(layer "B.Fab")
		)
		(fp_line
			(start -0.12065 -0.2794)
			(end -0.12065 -0.3048)
			(stroke
				(width 0.1)
				(type default)
			)
			(layer "B.Fab")
		)
		(fp_line
			(start 0.12065 0.2794)
			(end 0.12065 0.3048)
			(stroke
				(width 0.1)
				(type default)
			)
			(layer "B.Fab")
		)
		(fp_line
			(start -0.120396 0.2794)
			(end 0.12065 0.2794)
			(stroke
				(width 0.1)
				(type default)
			)
			(layer "B.Fab")
		)
		(fp_line
			(start 0.67945 0.3048)
			(end 0.67945 -0.305054)
			(stroke
				(width 0.1)
				(type default)
			)
			(layer "B.Fab")
		)
		(fp_line
			(start 0.12065 0.3048)
			(end 0.67945 0.3048)
			(stroke
				(width 0.1)
				(type default)
			)
			(layer "B.Fab")
		)
		(fp_line
			(start -0.120396 0.3048)
			(end -0.120396 0.2794)
			(stroke
				(width 0.1)
				(type default)
			)
			(layer "B.Fab")
		)
		(fp_line
			(start -0.67945 0.3048)
			(end -0.120396 0.3048)
			(stroke
				(width 0.1)
				(type default)
			)
			(layer "B.Fab")
		)
		(pad "1" smd circle
			(at 0.40005 0 270)
			(size 0 0)
			(layers "B.Cu" "B.Mask" "B.Paste")
			(net "P0V9_RETIMER_CPU1_VRHOT")
		)
		(pad "2" smd circle
			(at -0.40005 0 270)
			(size 0 0)
			(layers "B.Cu" "B.Mask" "B.Paste")
			(net "TP_P0V9_RETIMER_CPU1_VRHOT")
		)
	)
	(footprint ""
		(layer "B.Cu")
		(at 159.926782 -347.663008 180)
		(property "Reference" "PR390"
			(at 0 0 0)
			(layer "B.SilkS")
			(hide yes)
			(effects
				(font
					(size 1.27 1.27)
				)
				(justify mirror)
			)
		)
		(property "Value" ""
			(at 0 0 0)
			(layer "B.Fab")
			(effects
				(font
					(size 1.27 1.27)
				)
				(justify mirror)
			)
		)
		(duplicate_pad_numbers_are_jumpers no)
		(fp_line
			(start 0.7874 0.4064)
			(end 0.7874 -0.4064)
			(stroke
				(width 0.1524)
				(type default)
			)
			(layer "B.SilkS")
		)
		(fp_line
			(start 0.7874 -0.4064)
			(end -0.7874 -0.4064)
			(stroke
				(width 0.1524)
				(type default)
			)
			(layer "B.SilkS")
		)
		(fp_line
			(start -0.7874 0.4064)
			(end 0.7874 0.4064)
			(stroke
				(width 0.1524)
				(type default)
			)
			(layer "B.SilkS")
		)
		(fp_line
			(start -0.7874 -0.4064)
			(end -0.7874 0.4064)
			(stroke
				(width 0.1524)
				(type default)
			)
			(layer "B.SilkS")
		)
		(fp_line
			(start 0.67945 0.3048)
			(end 0.67945 -0.305054)
			(stroke
				(width 0.1)
				(type default)
			)
			(layer "B.Fab")
		)
		(fp_line
			(start 0.67945 -0.305054)
			(end 0.12065 -0.305054)
			(stroke
				(width 0.1)
				(type default)
			)
			(layer "B.Fab")
		)
		(fp_line
			(start 0.12065 0.3048)
			(end 0.67945 0.3048)
			(stroke
				(width 0.1)
				(type default)
			)
			(layer "B.Fab")
		)
		(fp_line
			(start 0.12065 0.2794)
			(end 0.12065 0.3048)
			(stroke
				(width 0.1)
				(type default)
			)
			(layer "B.Fab")
		)
		(fp_line
			(start 0.12065 -0.2794)
			(end -0.12065 -0.2794)
			(stroke
				(width 0.1)
				(type default)
			)
			(layer "B.Fab")
		)
		(fp_line
			(start 0.12065 -0.305054)
			(end 0.12065 -0.2794)
			(stroke
				(width 0.1)
				(type default)
			)
			(layer "B.Fab")
		)
		(fp_line
			(start -0.120396 0.3048)
			(end -0.120396 0.2794)
			(stroke
				(width 0.1)
				(type default)
			)
			(layer "B.Fab")
		)
		(fp_line
			(start -0.120396 0.2794)
			(end 0.12065 0.2794)
			(stroke
				(width 0.1)
				(type default)
			)
			(layer "B.Fab")
		)
		(fp_line
			(start -0.12065 -0.2794)
			(end -0.12065 -0.3048)
			(stroke
				(width 0.1)
				(type default)
			)
			(layer "B.Fab")
		)
		(fp_line
			(start -0.12065 -0.3048)
			(end -0.67945 -0.3048)
			(stroke
				(width 0.1)
				(type default)
			)
			(layer "B.Fab")
		)
		(fp_line
			(start -0.67945 0.3048)
			(end -0.120396 0.3048)
			(stroke
				(width 0.1)
				(type default)
			)
			(layer "B.Fab")
		)
		(fp_line
			(start -0.67945 -0.3048)
			(end -0.67945 0.3048)
			(stroke
				(width 0.1)
				(type default)
			)
			(layer "B.Fab")
		)
		(pad "1" smd circle
			(at 0.40005 0)
			(size 0 0)
			(layers "B.Cu" "B.Mask" "B.Paste")
			(net "PVDD11_S3_P1_RESET_N_R")
		)
		(pad "2" smd circle
			(at -0.40005 0)
			(size 0 0)
			(layers "B.Cu" "B.Mask" "B.Paste")
			(net "GND")
		)
	)
	(footprint ""
		(layer "B.Cu")
		(at 183.3753 -401.918932 -90)
		(property "Reference" "PC2186"
			(at 0 0 90)
			(layer "B.SilkS")
			(hide yes)
			(effects
				(font
					(size 1.27 1.27)
				)
				(justify mirror)
			)
		)
		(property "Value" ""
			(at 0 0 90)
			(layer "B.Fab")
			(effects
				(font
					(size 1.27 1.27)
				)
				(justify mirror)
			)
		)
		(duplicate_pad_numbers_are_jumpers no)
		(fp_line
			(start -0.7874 0.4064)
			(end 0.7874 0.4064)
			(stroke
				(width 0.1524)
				(type default)
			)
			(layer "B.SilkS")
		)
		(fp_line
			(start 0.7874 0.4064)
			(end 0.7874 -0.4064)
			(stroke
				(width 0.1524)
				(type default)
			)
			(layer "B.SilkS")
		)
		(fp_line
			(start -0.7874 -0.4064)
			(end -0.7874 0.4064)
			(stroke
				(width 0.1524)
				(type default)
			)
			(layer "B.SilkS")
		)
		(fp_line
			(start 0.7874 -0.4064)
			(end -0.7874 -0.4064)
			(stroke
				(width 0.1524)
				(type default)
			)
			(layer "B.SilkS")
		)
		(fp_line
			(start -0.67945 0.3048)
			(end -0.120396 0.3048)
			(stroke
				(width 0.1)
				(type default)
			)
			(layer "B.Fab")
		)
		(fp_line
			(start -0.120396 0.3048)
			(end -0.120396 0.2794)
			(stroke
				(width 0.1)
				(type default)
			)
			(layer "B.Fab")
		)
		(fp_line
			(start 0.12065 0.3048)
			(end 0.67945 0.3048)
			(stroke
				(width 0.1)
				(type default)
			)
			(layer "B.Fab")
		)
		(fp_line
			(start 0.67945 0.3048)
			(end 0.67945 -0.305054)
			(stroke
				(width 0.1)
				(type default)
			)
			(layer "B.Fab")
		)
		(fp_line
			(start -0.120396 0.2794)
			(end 0.12065 0.2794)
			(stroke
				(width 0.1)
				(type default)
			)
			(layer "B.Fab")
		)
		(fp_line
			(start 0.12065 0.2794)
			(end 0.12065 0.3048)
			(stroke
				(width 0.1)
				(type default)
			)
			(layer "B.Fab")
		)
		(fp_line
			(start -0.12065 -0.2794)
			(end -0.12065 -0.3048)
			(stroke
				(width 0.1)
				(type default)
			)
			(layer "B.Fab")
		)
		(fp_line
			(start 0.12065 -0.2794)
			(end -0.12065 -0.2794)
			(stroke
				(width 0.1)
				(type default)
			)
			(layer "B.Fab")
		)
		(fp_line
			(start -0.67945 -0.3048)
			(end -0.67945 0.3048)
			(stroke
				(width 0.1)
				(type default)
			)
			(layer "B.Fab")
		)
		(fp_line
			(start -0.12065 -0.3048)
			(end -0.67945 -0.3048)
			(stroke
				(width 0.1)
				(type default)
			)
			(layer "B.Fab")
		)
		(fp_line
			(start 0.12065 -0.305054)
			(end 0.12065 -0.2794)
			(stroke
				(width 0.1)
				(type default)
			)
			(layer "B.Fab")
		)
		(fp_line
			(start 0.67945 -0.305054)
			(end 0.12065 -0.305054)
			(stroke
				(width 0.1)
				(type default)
			)
			(layer "B.Fab")
		)
		(pad "1" smd circle
			(at 0.40005 0 90)
			(size 0 0)
			(layers "B.Cu" "B.Mask" "B.Paste")
			(net "HSC_VDD_R")
		)
		(pad "2" smd circle
			(at -0.40005 0 90)
			(size 0 0)
			(layers "B.Cu" "B.Mask" "B.Paste")
			(net "AGND_HSC")
		)
	)
	(footprint ""
		(layer "B.Cu")
		(at 332.187296 -151.132794 90)
		(property "Reference" "PR439"
			(at 0 0 90)
			(layer "B.SilkS")
			(hide yes)
			(effects
				(font
					(size 1.27 1.27)
				)
				(justify mirror)
			)
		)
		(property "Value" ""
			(at 0 0 90)
			(layer "B.Fab")
			(effects
				(font
					(size 1.27 1.27)
				)
				(justify mirror)
			)
		)
		(duplicate_pad_numbers_are_jumpers no)
		(fp_line
			(start 0.7874 -0.4064)
			(end -0.7874 -0.4064)
			(stroke
				(width 0.1524)
				(type default)
			)
			(layer "B.SilkS")
		)
		(fp_line
			(start -0.7874 -0.4064)
			(end -0.7874 0.4064)
			(stroke
				(width 0.1524)
				(type default)
			)
			(layer "B.SilkS")
		)
		(fp_line
			(start 0.7874 0.4064)
			(end 0.7874 -0.4064)
			(stroke
				(width 0.1524)
				(type default)
			)
			(layer "B.SilkS")
		)
		(fp_line
			(start -0.7874 0.4064)
			(end 0.7874 0.4064)
			(stroke
				(width 0.1524)
				(type default)
			)
			(layer "B.SilkS")
		)
		(fp_line
			(start 0.67945 -0.305054)
			(end 0.12065 -0.305054)
			(stroke
				(width 0.1)
				(type default)
			)
			(layer "B.Fab")
		)
		(fp_line
			(start 0.12065 -0.305054)
			(end 0.12065 -0.2794)
			(stroke
				(width 0.1)
				(type default)
			)
			(layer "B.Fab")
		)
		(fp_line
			(start -0.12065 -0.3048)
			(end -0.67945 -0.3048)
			(stroke
				(width 0.1)
				(type default)
			)
			(layer "B.Fab")
		)
		(fp_line
			(start -0.67945 -0.3048)
			(end -0.67945 0.3048)
			(stroke
				(width 0.1)
				(type default)
			)
			(layer "B.Fab")
		)
		(fp_line
			(start 0.12065 -0.2794)
			(end -0.12065 -0.2794)
			(stroke
				(width 0.1)
				(type default)
			)
			(layer "B.Fab")
		)
		(fp_line
			(start -0.12065 -0.2794)
			(end -0.12065 -0.3048)
			(stroke
				(width 0.1)
				(type default)
			)
			(layer "B.Fab")
		)
		(fp_line
			(start 0.12065 0.2794)
			(end 0.12065 0.3048)
			(stroke
				(width 0.1)
				(type default)
			)
			(layer "B.Fab")
		)
		(fp_line
			(start -0.120396 0.2794)
			(end 0.12065 0.2794)
			(stroke
				(width 0.1)
				(type default)
			)
			(layer "B.Fab")
		)
		(fp_line
			(start 0.67945 0.3048)
			(end 0.67945 -0.305054)
			(stroke
				(width 0.1)
				(type default)
			)
			(layer "B.Fab")
		)
		(fp_line
			(start 0.12065 0.3048)
			(end 0.67945 0.3048)
			(stroke
				(width 0.1)
				(type default)
			)
			(layer "B.Fab")
		)
		(fp_line
			(start -0.120396 0.3048)
			(end -0.120396 0.2794)
			(stroke
				(width 0.1)
				(type default)
			)
			(layer "B.Fab")
		)
		(fp_line
			(start -0.67945 0.3048)
			(end -0.120396 0.3048)
			(stroke
				(width 0.1)
				(type default)
			)
			(layer "B.Fab")
		)
		(pad "1" smd circle
			(at 0.40005 0 270)
			(size 0 0)
			(layers "B.Cu" "B.Mask" "B.Paste")
			(net "PVDD18_S5_P0")
		)
		(pad "2" smd circle
			(at -0.40005 0 270)
			(size 0 0)
			(layers "B.Cu" "B.Mask" "B.Paste")
			(net "GND")
		)
	)
)
